(kicad_pcb
	(version 20260206)
	(generator "pcbnew")
	(generator_version "10.0")
	(general
		(thickness 1.6)
		(legacy_teardrops no)
	)
	(paper "A4")
	(title_block
		(title "Bryce Canyon_R.DPB_16317-1_OCP.brd")
		(comment 1 "Bryce Canyon / footprints 1015-1021 of 2099")
	)
	(layers
		(0 "F.Cu" signal "TOP")
		(4 "In1.Cu" signal "L2GND")
		(6 "In2.Cu" signal "L3")
		(8 "In3.Cu" signal "L4VCC")
		(10 "In4.Cu" signal "L5VCC")
		(12 "In5.Cu" signal "L6")
		(14 "In6.Cu" signal "L7GND")
		(2 "B.Cu" signal "BOTTOM")
		(9 "F.Adhes" user "F.Adhesive")
		(11 "B.Adhes" user "B.Adhesive")
		(13 "F.Paste" user "Package Geometry/Pastemask Top")
		(15 "B.Paste" user "Package Geometry/Pastemask Bottom")
		(5 "F.SilkS" user "Ref Des/Silkscreen Top")
		(7 "B.SilkS" user "Ref Des/Silkscreen Bottom")
		(1 "F.Mask" user "Board Geometry/Soldermask Top")
		(3 "B.Mask" user "Board Geometry/Soldermask Bottom")
		(17 "Dwgs.User" user "User.Drawings")
		(19 "Cmts.User" user "User.Comments")
		(21 "Eco1.User" user "User.Eco1")
		(23 "Eco2.User" user "User.Eco2")
		(25 "Edge.Cuts" user "Board Geometry/Outline")
		(27 "Margin" user)
		(31 "F.CrtYd" user "Package Geometry/Place Bound Top")
		(29 "B.CrtYd" user "Package Geometry/Place Bound Bottom")
		(35 "F.Fab" user "Ref Des/Assembly Top")
		(33 "B.Fab" user "Ref Des/Assembly Bottom")
	)
	(footprint ""
		(layer "F.Cu")
		(at 460.060802 -230.63835 -90)
		(property "Reference" "R1138"
			(at 0 0 270)
			(layer "F.SilkS")
			(hide yes)
			(effects
				(font
					(size 1.27 1.27)
				)
			)
		)
		(property "Value" "10KR2F-2-GP"
			(at 0.064008 -3.993896 270)
			(unlocked yes)
			(layer "F.Fab")
			(hide yes)
			(effects
				(font
					(size 1.016 1.016)
					(thickness 0.1524)
				)
			)
		)
		(property "Device Type" "R402H16"
			(at 0.064008 -5.517896 270)
			(unlocked yes)
			(layer "F.Fab")
			(hide yes)
			(effects
				(font
					(size 1.016 1.016)
					(thickness 0.1524)
				)
			)
		)
		(duplicate_pad_numbers_are_jumpers no)
		(fp_line
			(start -0.508 -0.9398)
			(end -0.508 0.9398)
			(stroke
				(width 0.1524)
				(type default)
			)
			(layer "F.SilkS")
		)
		(fp_line
			(start 0.508 -0.9398)
			(end -0.508 -0.9398)
			(stroke
				(width 0.1524)
				(type default)
			)
			(layer "F.SilkS")
		)
		(fp_rect
			(start -0.508 0.9398)
			(end 0.508 -0.9398)
			(stroke
				(width 0)
				(type default)
			)
			(fill no)
			(layer "F.CrtYd")
		)
		(fp_rect
			(start -0.508 0.9398)
			(end 0.508 -0.9398)
			(stroke
				(width 0)
				(type default)
			)
			(fill no)
			(layer "F.Fab")
		)
		(pad "1" smd custom
			(at 0 -0.4445 270)
			(size 0.1397 0.1397)
			(layers "F.Cu" "F.Mask" "F.Paste")
			(net "P5V_B_3_EN_R")
			(options
				(clearance outline)
				(anchor circle)
			)
			(primitives
				(gr_poly
					(pts
						(arc
							(start -0.1778 -0.2794)
							(mid -0.249642 -0.249642)
							(end -0.2794 -0.1778)
						)
						(arc
							(start -0.2794 0.1778)
							(mid -0.249642 0.249642)
							(end -0.1778 0.2794)
						)
						(arc
							(start 0.1778 0.2794)
							(mid 0.249642 0.249642)
							(end 0.2794 0.1778)
						)
						(arc
							(start 0.2794 -0.1778)
							(mid 0.249642 -0.249642)
							(end 0.1778 -0.2794)
						)
					)
					(width 0)
					(fill yes)
				)
			)
		)
		(pad "2" smd custom
			(at 0 0.4445 270)
			(size 0.1397 0.1397)
			(layers "F.Cu" "F.Mask" "F.Paste")
			(net "GND")
			(options
				(clearance outline)
				(anchor circle)
			)
			(primitives
				(gr_poly
					(pts
						(arc
							(start -0.1778 -0.2794)
							(mid -0.249642 -0.249642)
							(end -0.2794 -0.1778)
						)
						(arc
							(start -0.2794 0.1778)
							(mid -0.249642 0.249642)
							(end -0.1778 0.2794)
						)
						(arc
							(start 0.1778 0.2794)
							(mid 0.249642 0.249642)
							(end 0.2794 0.1778)
						)
						(arc
							(start 0.2794 -0.1778)
							(mid 0.249642 -0.249642)
							(end 0.1778 -0.2794)
						)
					)
					(width 0)
					(fill yes)
				)
			)
		)
	)
	(footprint ""
		(layer "F.Cu")
		(at 361.315 -267.843 180)
		(property "Reference" "C121"
			(at 0 0 180)
			(layer "F.SilkS")
			(hide yes)
			(effects
				(font
					(size 1.27 1.27)
				)
			)
		)
		(property "Value" "SC1U16V3KX-5GP"
			(at 0 -2.8194 180)
			(unlocked yes)
			(layer "F.Fab")
			(hide yes)
			(effects
				(font
					(size 1.016 1.016)
					(thickness 0.1524)
				)
			)
		)
		(property "Device Type" "C603H36"
			(at 0 -4.3434 180)
			(unlocked yes)
			(layer "F.Fab")
			(hide yes)
			(effects
				(font
					(size 1.016 1.016)
					(thickness 0.1524)
				)
			)
		)
		(duplicate_pad_numbers_are_jumpers no)
		(fp_line
			(start 0.508 0)
			(end -0.508 0)
			(stroke
				(width 0.2032)
				(type default)
			)
			(layer "F.SilkS")
		)
		(fp_rect
			(start -0.5842 1.3335)
			(end 0.5842 -1.3335)
			(stroke
				(width 0)
				(type default)
			)
			(fill no)
			(layer "F.CrtYd")
		)
		(fp_rect
			(start -0.5842 1.3335)
			(end 0.5842 -1.3335)
			(stroke
				(width 0)
				(type default)
			)
			(fill no)
			(layer "F.Fab")
		)
		(pad "1" smd custom
			(at 0 -0.762 180)
			(size 0.2159 0.2159)
			(layers "F.Cu" "F.Mask" "F.Paste")
			(net "P5V_HDD7")
			(options
				(clearance outline)
				(anchor circle)
			)
			(primitives
				(gr_poly
					(pts
						(arc
							(start -0.3302 -0.4318)
							(mid -0.402042 -0.402042)
							(end -0.4318 -0.3302)
						)
						(arc
							(start -0.4318 0.3302)
							(mid -0.402042 0.402042)
							(end -0.3302 0.4318)
						)
						(arc
							(start 0.3302 0.4318)
							(mid 0.402042 0.402042)
							(end 0.4318 0.3302)
						)
						(arc
							(start 0.4318 -0.3302)
							(mid 0.402042 -0.402042)
							(end 0.3302 -0.4318)
						)
					)
					(width 0)
					(fill yes)
				)
			)
		)
		(pad "2" smd custom
			(at 0 0.762 180)
			(size 0.2159 0.2159)
			(layers "F.Cu" "F.Mask" "F.Paste")
			(net "GND")
			(options
				(clearance outline)
				(anchor circle)
			)
			(primitives
				(gr_poly
					(pts
						(arc
							(start -0.3302 -0.4318)
							(mid -0.402042 -0.402042)
							(end -0.4318 -0.3302)
						)
						(arc
							(start -0.4318 0.3302)
							(mid -0.402042 0.402042)
							(end -0.3302 0.4318)
						)
						(arc
							(start 0.3302 0.4318)
							(mid 0.402042 0.402042)
							(end 0.4318 0.3302)
						)
						(arc
							(start 0.4318 -0.3302)
							(mid 0.402042 -0.402042)
							(end 0.3302 -0.4318)
						)
					)
					(width 0)
					(fill yes)
				)
			)
		)
	)
	(footprint ""
		(layer "F.Cu")
		(at 219.142564 -107.414568)
		(property "Reference" "R142"
			(at 0 0 0)
			(layer "F.SilkS")
			(hide yes)
			(effects
				(font
					(size 1.27 1.27)
				)
			)
		)
		(property "Value" "1KR2F-3-GP"
			(at 0.064008 -3.993896 0)
			(unlocked yes)
			(layer "F.Fab")
			(hide yes)
			(effects
				(font
					(size 1.016 1.016)
					(thickness 0.1524)
				)
			)
		)
		(property "Device Type" "R402H16"
			(at 0.064008 -5.517896 0)
			(unlocked yes)
			(layer "F.Fab")
			(hide yes)
			(effects
				(font
					(size 1.016 1.016)
					(thickness 0.1524)
				)
			)
		)
		(duplicate_pad_numbers_are_jumpers no)
		(fp_line
			(start -0.508 -0.9398)
			(end -0.508 0.9398)
			(stroke
				(width 0.1524)
				(type default)
			)
			(layer "F.SilkS")
		)
		(fp_line
			(start 0.508 -0.9398)
			(end -0.508 -0.9398)
			(stroke
				(width 0.1524)
				(type default)
			)
			(layer "F.SilkS")
		)
		(fp_rect
			(start -0.508 0.9398)
			(end 0.508 -0.9398)
			(stroke
				(width 0)
				(type default)
			)
			(fill no)
			(layer "F.CrtYd")
		)
		(fp_rect
			(start -0.508 0.9398)
			(end 0.508 -0.9398)
			(stroke
				(width 0)
				(type default)
			)
			(fill no)
			(layer "F.Fab")
		)
		(pad "1" smd custom
			(at 0 -0.4445)
			(size 0.1397 0.1397)
			(layers "F.Cu" "F.Mask" "F.Paste")
			(net "P3V3_STBY_B")
			(options
				(clearance outline)
				(anchor circle)
			)
			(primitives
				(gr_poly
					(pts
						(arc
							(start -0.1778 -0.2794)
							(mid -0.249642 -0.249642)
							(end -0.2794 -0.1778)
						)
						(arc
							(start -0.2794 0.1778)
							(mid -0.249642 0.249642)
							(end -0.1778 0.2794)
						)
						(arc
							(start 0.1778 0.2794)
							(mid 0.249642 0.249642)
							(end 0.2794 0.1778)
						)
						(arc
							(start 0.2794 -0.1778)
							(mid 0.249642 -0.249642)
							(end 0.1778 -0.2794)
						)
					)
					(width 0)
					(fill yes)
				)
			)
		)
		(pad "2" smd custom
			(at 0 0.4445)
			(size 0.1397 0.1397)
			(layers "F.Cu" "F.Mask" "F.Paste")
			(net "I2C_BMC_B_EXP_B_SDA")
			(options
				(clearance outline)
				(anchor circle)
			)
			(primitives
				(gr_poly
					(pts
						(arc
							(start -0.1778 -0.2794)
							(mid -0.249642 -0.249642)
							(end -0.2794 -0.1778)
						)
						(arc
							(start -0.2794 0.1778)
							(mid -0.249642 0.249642)
							(end -0.1778 0.2794)
						)
						(arc
							(start 0.1778 0.2794)
							(mid 0.249642 0.249642)
							(end 0.2794 0.1778)
						)
						(arc
							(start 0.2794 -0.1778)
							(mid 0.249642 -0.249642)
							(end 0.1778 -0.2794)
						)
					)
					(width 0)
					(fill yes)
				)
			)
		)
	)
	(footprint ""
		(layer "F.Cu")
		(at 182.118 -19.177)
		(property "Reference" "R748"
			(at 0 0 0)
			(layer "F.SilkS")
			(hide yes)
			(effects
				(font
					(size 1.27 1.27)
				)
			)
		)
		(property "Value" "0R2J-2-GP"
			(at 0.064008 -3.993896 0)
			(unlocked yes)
			(layer "F.Fab")
			(hide yes)
			(effects
				(font
					(size 1.016 1.016)
					(thickness 0.1524)
				)
			)
		)
		(property "Device Type" "R402H16"
			(at 0.064008 -5.517896 0)
			(unlocked yes)
			(layer "F.Fab")
			(hide yes)
			(effects
				(font
					(size 1.016 1.016)
					(thickness 0.1524)
				)
			)
		)
		(duplicate_pad_numbers_are_jumpers no)
		(fp_line
			(start -0.508 -0.9398)
			(end -0.508 0.9398)
			(stroke
				(width 0.1524)
				(type default)
			)
			(layer "F.SilkS")
		)
		(fp_line
			(start 0.508 -0.9398)
			(end -0.508 -0.9398)
			(stroke
				(width 0.1524)
				(type default)
			)
			(layer "F.SilkS")
		)
		(fp_rect
			(start -0.508 0.9398)
			(end 0.508 -0.9398)
			(stroke
				(width 0)
				(type default)
			)
			(fill no)
			(layer "F.CrtYd")
		)
		(fp_rect
			(start -0.508 0.9398)
			(end 0.508 -0.9398)
			(stroke
				(width 0)
				(type default)
			)
			(fill no)
			(layer "F.Fab")
		)
		(pad "1" smd custom
			(at 0 -0.4445)
			(size 0.1397 0.1397)
			(layers "F.Cu" "F.Mask" "F.Paste")
			(net "DRIVE_B_29_PWR")
			(options
				(clearance outline)
				(anchor circle)
			)
			(primitives
				(gr_poly
					(pts
						(arc
							(start -0.1778 -0.2794)
							(mid -0.249642 -0.249642)
							(end -0.2794 -0.1778)
						)
						(arc
							(start -0.2794 0.1778)
							(mid -0.249642 0.249642)
							(end -0.1778 0.2794)
						)
						(arc
							(start 0.1778 0.2794)
							(mid 0.249642 0.249642)
							(end 0.2794 0.1778)
						)
						(arc
							(start 0.2794 -0.1778)
							(mid 0.249642 -0.249642)
							(end 0.1778 -0.2794)
						)
					)
					(width 0)
					(fill yes)
				)
			)
		)
		(pad "2" smd custom
			(at 0 0.4445)
			(size 0.1397 0.1397)
			(layers "F.Cu" "F.Mask" "F.Paste")
			(net "SW_PWR_R_HDD29")
			(options
				(clearance outline)
				(anchor circle)
			)
			(primitives
				(gr_poly
					(pts
						(arc
							(start -0.1778 -0.2794)
							(mid -0.249642 -0.249642)
							(end -0.2794 -0.1778)
						)
						(arc
							(start -0.2794 0.1778)
							(mid -0.249642 0.249642)
							(end -0.1778 0.2794)
						)
						(arc
							(start 0.1778 0.2794)
							(mid 0.249642 0.249642)
							(end 0.2794 0.1778)
						)
						(arc
							(start 0.2794 -0.1778)
							(mid 0.249642 -0.249642)
							(end 0.1778 -0.2794)
						)
					)
					(width 0)
					(fill yes)
				)
			)
		)
	)
	(footprint ""
		(layer "F.Cu")
		(at 64.0588 -18.750026 -90)
		(property "Reference" "VIA52"
			(at 0 0 270)
			(layer "F.SilkS")
			(hide yes)
			(effects
				(font
					(size 1.27 1.27)
				)
			)
		)
		(property "Value" "100OHM-8L-2D36MM-L16-GP"
			(at -3.4036 -0.4572 270)
			(unlocked yes)
			(layer "F.Fab")
			(hide yes)
			(effects
				(font
					(size 1.016 1.016)
					(thickness 0.1524)
				)
			)
		)
		(property "Device Type" "VIA-PCIE-4P-427097"
			(at -3.4036 -1.9812 270)
			(unlocked yes)
			(layer "F.Fab")
			(hide yes)
			(effects
				(font
					(size 1.016 1.016)
					(thickness 0.1524)
				)
			)
		)
		(duplicate_pad_numbers_are_jumpers no)
		(fp_rect
			(start -2.1336 0.4826)
			(end 2.1336 -0.4826)
			(stroke
				(width 0)
				(type default)
			)
			(fill no)
			(layer "F.CrtYd")
		)
		(fp_rect
			(start -2.1336 0.4826)
			(end 2.1336 -0.4826)
			(stroke
				(width 0)
				(type default)
			)
			(fill no)
			(layer "F.Fab")
		)
		(pad "1" thru_hole circle
			(at -1.651 0 270)
			(size 0.508 0.508)
			(drill 0.254)
			(layers "*.Cu" "*.Mask")
			(remove_unused_layers no)
			(net "GND")
			(clearance 0.2286)
			(thermal_gap 0.2286)
		)
		(pad "2" thru_hole circle
			(at -0.635 0 270)
			(size 0.508 0.508)
			(drill 0.254)
			(layers "*.Cu" "*.Mask")
			(remove_unused_layers no)
			(net "PHY_DRV_B_TO_SCC_B_25_DP")
			(clearance 0.2286)
			(thermal_gap 0.2286)
		)
		(pad "3" thru_hole circle
			(at 0.635 0 270)
			(size 0.508 0.508)
			(drill 0.254)
			(layers "*.Cu" "*.Mask")
			(remove_unused_layers no)
			(net "PHY_DRV_B_TO_SCC_B_25_DN")
			(clearance 0.2286)
			(thermal_gap 0.2286)
		)
		(pad "4" thru_hole circle
			(at 1.651 0 270)
			(size 0.508 0.508)
			(drill 0.254)
			(layers "*.Cu" "*.Mask")
			(remove_unused_layers no)
			(net "GND")
			(clearance 0.2286)
			(thermal_gap 0.2286)
		)
	)
	(footprint ""
		(layer "F.Cu")
		(at 231.07904 -233.01198)
		(property "Reference" "R65"
			(at 0 0 0)
			(layer "F.SilkS")
			(hide yes)
			(effects
				(font
					(size 1.27 1.27)
				)
			)
		)
		(property "Value" "4K7R2F-GP"
			(at 0.064008 -3.993896 0)
			(unlocked yes)
			(layer "F.Fab")
			(hide yes)
			(effects
				(font
					(size 1.016 1.016)
					(thickness 0.1524)
				)
			)
		)
		(property "Device Type" "R402H16"
			(at 0.064008 -5.517896 0)
			(unlocked yes)
			(layer "F.Fab")
			(hide yes)
			(effects
				(font
					(size 1.016 1.016)
					(thickness 0.1524)
				)
			)
		)
		(duplicate_pad_numbers_are_jumpers no)
		(fp_line
			(start -0.508 -0.9398)
			(end -0.508 0.9398)
			(stroke
				(width 0.1524)
				(type default)
			)
			(layer "F.SilkS")
		)
		(fp_line
			(start 0.508 -0.9398)
			(end -0.508 -0.9398)
			(stroke
				(width 0.1524)
				(type default)
			)
			(layer "F.SilkS")
		)
		(fp_rect
			(start -0.508 0.9398)
			(end 0.508 -0.9398)
			(stroke
				(width 0)
				(type default)
			)
			(fill no)
			(layer "F.CrtYd")
		)
		(fp_rect
			(start -0.508 0.9398)
			(end 0.508 -0.9398)
			(stroke
				(width 0)
				(type default)
			)
			(fill no)
			(layer "F.Fab")
		)
		(pad "1" smd custom
			(at 0 -0.4445)
			(size 0.1397 0.1397)
			(layers "F.Cu" "F.Mask" "F.Paste")
			(net "P3V3_STBY_B")
			(options
				(clearance outline)
				(anchor circle)
			)
			(primitives
				(gr_poly
					(pts
						(arc
							(start -0.1778 -0.2794)
							(mid -0.249642 -0.249642)
							(end -0.2794 -0.1778)
						)
						(arc
							(start -0.2794 0.1778)
							(mid -0.249642 0.249642)
							(end -0.1778 0.2794)
						)
						(arc
							(start 0.1778 0.2794)
							(mid 0.249642 0.249642)
							(end 0.2794 0.1778)
						)
						(arc
							(start 0.2794 -0.1778)
							(mid 0.249642 -0.249642)
							(end 0.1778 -0.2794)
						)
					)
					(width 0)
					(fill yes)
				)
			)
		)
		(pad "2" smd custom
			(at 0 0.4445)
			(size 0.1397 0.1397)
			(layers "F.Cu" "F.Mask" "F.Paste")
			(net "IO_EXP1_A2")
			(options
				(clearance outline)
				(anchor circle)
			)
			(primitives
				(gr_poly
					(pts
						(arc
							(start -0.1778 -0.2794)
							(mid -0.249642 -0.249642)
							(end -0.2794 -0.1778)
						)
						(arc
							(start -0.2794 0.1778)
							(mid -0.249642 0.249642)
							(end -0.1778 0.2794)
						)
						(arc
							(start 0.1778 0.2794)
							(mid 0.249642 0.249642)
							(end 0.2794 0.1778)
						)
						(arc
							(start 0.2794 -0.1778)
							(mid 0.249642 -0.249642)
							(end 0.1778 -0.2794)
						)
					)
					(width 0)
					(fill yes)
				)
			)
		)
	)
	(footprint ""
		(layer "F.Cu")
		(at 315.3664 -340.812882)
		(property "Reference" "R120"
			(at 0 0 0)
			(layer "F.SilkS")
			(hide yes)
			(effects
				(font
					(size 1.27 1.27)
				)
			)
		)
		(property "Value" "4K7R2F-GP"
			(at 0.064008 -3.993896 0)
			(unlocked yes)
			(layer "F.Fab")
			(hide yes)
			(effects
				(font
					(size 1.016 1.016)
					(thickness 0.1524)
				)
			)
		)
		(property "Device Type" "R402H16"
			(at 0.064008 -5.517896 0)
			(unlocked yes)
			(layer "F.Fab")
			(hide yes)
			(effects
				(font
					(size 1.016 1.016)
					(thickness 0.1524)
				)
			)
		)
		(duplicate_pad_numbers_are_jumpers no)
		(fp_line
			(start -0.508 -0.9398)
			(end -0.508 0.9398)
			(stroke
				(width 0.1524)
				(type default)
			)
			(layer "F.SilkS")
		)
		(fp_line
			(start 0.508 -0.9398)
			(end -0.508 -0.9398)
			(stroke
				(width 0.1524)
				(type default)
			)
			(layer "F.SilkS")
		)
		(fp_rect
			(start -0.508 0.9398)
			(end 0.508 -0.9398)
			(stroke
				(width 0)
				(type default)
			)
			(fill no)
			(layer "F.CrtYd")
		)
		(fp_rect
			(start -0.508 0.9398)
			(end 0.508 -0.9398)
			(stroke
				(width 0)
				(type default)
			)
			(fill no)
			(layer "F.Fab")
		)
		(pad "1" smd custom
			(at 0 -0.4445)
			(size 0.1397 0.1397)
			(layers "F.Cu" "F.Mask" "F.Paste")
			(net "P3V3_IN")
			(options
				(clearance outline)
				(anchor circle)
			)
			(primitives
				(gr_poly
					(pts
						(arc
							(start -0.1778 -0.2794)
							(mid -0.249642 -0.249642)
							(end -0.2794 -0.1778)
						)
						(arc
							(start -0.2794 0.1778)
							(mid -0.249642 0.249642)
							(end -0.1778 0.2794)
						)
						(arc
							(start 0.1778 0.2794)
							(mid 0.249642 0.249642)
							(end 0.2794 0.1778)
						)
						(arc
							(start 0.2794 -0.1778)
							(mid 0.249642 -0.249642)
							(end 0.1778 -0.2794)
						)
					)
					(width 0)
					(fill yes)
				)
			)
		)
		(pad "2" smd custom
			(at 0 0.4445)
			(size 0.1397 0.1397)
			(layers "F.Cu" "F.Mask" "F.Paste")
			(net "PWM_CAMP_SEL2")
			(options
				(clearance outline)
				(anchor circle)
			)
			(primitives
				(gr_poly
					(pts
						(arc
							(start -0.1778 -0.2794)
							(mid -0.249642 -0.249642)
							(end -0.2794 -0.1778)
						)
						(arc
							(start -0.2794 0.1778)
							(mid -0.249642 0.249642)
							(end -0.1778 0.2794)
						)
						(arc
							(start 0.1778 0.2794)
							(mid 0.249642 0.249642)
							(end 0.2794 0.1778)
						)
						(arc
							(start 0.2794 -0.1778)
							(mid 0.249642 -0.249642)
							(end 0.1778 -0.2794)
						)
					)
					(width 0)
					(fill yes)
				)
			)
		)
	)
)
